# S9S_MB_2U (Grand Teton) — schematic netlist excerpt (pin names and nets, part order shuffled) for the footprints in the layout excerpt that follows; sources: Cadence DE-HDL packaged netlist, KiCad conversion of 03242023_DA0F0TMBIJ0_F0T_Motherboard_J_brd_V01_OCP.brd

C4  Q_CAP  10UF 16V 10% X6S  pkg C0805  page 82 : A = P12V_S3_AUX_CPU0_NVDIMM ; B = GND
C515  Q_CAP  47UF 4V 20% X6S  pkg C0805  page 75 : A = PVCCD_HV_CPU0 ; B = GND
R4390  Q_RES  150 1% CHIP  pkg 0402LF  page 225 : A = PVNN_TERM_CPU0 ; B = H_CPU_ERR0_LVC1_R_N

(kicad_pcb
	(version 20260206)
	(generator "pcbnew")
	(generator_version "10.0")
	(general
		(thickness 1.6)
		(legacy_teardrops no)
	)
	(paper "A4")
	(title_block
		(title "03242023_DA0F0TMBIJ0_F0T_Motherboard_J_brd_V01_OCP.brd")
		(comment 1 "Grand Teton / footprints 5776-5778 of 6105")
	)
	(layers
		(0 "F.Cu" signal "TOP")
		(4 "In1.Cu" signal "GND")
		(6 "In2.Cu" signal "IN1")
		(8 "In3.Cu" signal "GND1")
		(10 "In4.Cu" signal "IN2")
		(12 "In5.Cu" signal "GND2")
		(14 "In6.Cu" signal "IN3")
		(16 "In7.Cu" signal "GND3")
		(18 "In8.Cu" signal "VCC")
		(20 "In9.Cu" signal "VCC1")
		(22 "In10.Cu" signal "GND4")
		(24 "In11.Cu" signal "IN4")
		(26 "In12.Cu" signal "GND5")
		(28 "In13.Cu" signal "IN5")
		(30 "In14.Cu" signal "GND6")
		(32 "In15.Cu" signal "IN6")
		(34 "In16.Cu" signal "GND7")
		(2 "B.Cu" signal "BOTTOM")
		(9 "F.Adhes" user "F.Adhesive")
		(11 "B.Adhes" user "B.Adhesive")
		(13 "F.Paste" user "Package Geometry/Pastemask Top")
		(15 "B.Paste" user "Package Geometry/Pastemask Bottom")
		(5 "F.SilkS" user "Ref Des/Silkscreen Top")
		(7 "B.SilkS" user "Ref Des/Silkscreen Bottom")
		(1 "F.Mask" user "Board Geometry/Soldermask Top")
		(3 "B.Mask" user "Board Geometry/Soldermask Bottom")
		(17 "Dwgs.User" user "User.Drawings")
		(19 "Cmts.User" user "User.Comments")
		(21 "Eco1.User" user "User.Eco1")
		(23 "Eco2.User" user "User.Eco2")
		(25 "Edge.Cuts" user "Board Geometry/Outline")
		(27 "Margin" user)
		(31 "F.CrtYd" user "Package Geometry/Place Bound Top")
		(29 "B.CrtYd" user "Package Geometry/Place Bound Bottom")
		(35 "F.Fab" user "Ref Des/Assembly Top")
		(33 "B.Fab" user "Ref Des/Assembly Bottom")
	)
	(footprint ""
		(layer "B.Cu")
		(at 367.824258 -241.11585 90)
		(property "Reference" "C515"
			(at 0 0 90)
			(layer "B.SilkS")
			(hide yes)
			(effects
				(font
					(size 1.27 1.27)
				)
				(justify mirror)
			)
		)
		(property "Value" ""
			(at 0 0 90)
			(layer "B.Fab")
			(effects
				(font
					(size 1.27 1.27)
				)
				(justify mirror)
			)
		)
		(duplicate_pad_numbers_are_jumpers no)
		(fp_line
			(start 1.524 -0.762)
			(end -1.524 -0.762)
			(stroke
				(width 0.1524)
				(type default)
			)
			(layer "B.SilkS")
		)
		(fp_line
			(start -1.524 -0.762)
			(end -1.524 0.762)
			(stroke
				(width 0.1524)
				(type default)
			)
			(layer "B.SilkS")
		)
		(fp_line
			(start 1.524 0.762)
			(end 1.524 -0.762)
			(stroke
				(width 0.1524)
				(type default)
			)
			(layer "B.SilkS")
		)
		(fp_line
			(start -1.524 0.762)
			(end 1.524 0.762)
			(stroke
				(width 0.1524)
				(type default)
			)
			(layer "B.SilkS")
		)
		(fp_line
			(start 1.1049 -0.724916)
			(end 1.1049 0.724916)
			(stroke
				(width 0.1)
				(type default)
			)
			(layer "B.Fab")
		)
		(fp_line
			(start -1.1049 -0.724916)
			(end 1.1049 -0.724916)
			(stroke
				(width 0.1)
				(type default)
			)
			(layer "B.Fab")
		)
		(fp_line
			(start 1.1049 0.724916)
			(end -1.1049 0.724916)
			(stroke
				(width 0.1)
				(type default)
			)
			(layer "B.Fab")
		)
		(fp_line
			(start -1.1049 0.724916)
			(end -1.1049 -0.724916)
			(stroke
				(width 0.1)
				(type default)
			)
			(layer "B.Fab")
		)
		(pad "1" smd rect
			(at 0.889 0 90)
			(size 1.016 1.27)
			(layers "B.Cu" "B.Mask" "B.Paste")
			(net "PVCCD_HV_CPU0")
		)
		(pad "2" smd rect
			(at -0.889 0 90)
			(size 1.016 1.27)
			(layers "B.Cu" "B.Mask" "B.Paste")
			(net "GND")
		)
	)
	(footprint ""
		(layer "B.Cu")
		(at 301.356014 -321.549776 -90)
		(property "Reference" "C4"
			(at 0 0 90)
			(layer "B.SilkS")
			(hide yes)
			(effects
				(font
					(size 1.27 1.27)
				)
				(justify mirror)
			)
		)
		(property "Value" ""
			(at 0 0 90)
			(layer "B.Fab")
			(effects
				(font
					(size 1.27 1.27)
				)
				(justify mirror)
			)
		)
		(duplicate_pad_numbers_are_jumpers no)
		(fp_line
			(start -1.524 0.762)
			(end 1.524 0.762)
			(stroke
				(width 0.1524)
				(type default)
			)
			(layer "B.SilkS")
		)
		(fp_line
			(start 1.524 0.762)
			(end 1.524 -0.762)
			(stroke
				(width 0.1524)
				(type default)
			)
			(layer "B.SilkS")
		)
		(fp_line
			(start -1.524 -0.762)
			(end -1.524 0.762)
			(stroke
				(width 0.1524)
				(type default)
			)
			(layer "B.SilkS")
		)
		(fp_line
			(start 1.524 -0.762)
			(end -1.524 -0.762)
			(stroke
				(width 0.1524)
				(type default)
			)
			(layer "B.SilkS")
		)
		(fp_line
			(start -1.1049 0.724916)
			(end -1.1049 -0.724916)
			(stroke
				(width 0.1)
				(type default)
			)
			(layer "B.Fab")
		)
		(fp_line
			(start 1.1049 0.724916)
			(end -1.1049 0.724916)
			(stroke
				(width 0.1)
				(type default)
			)
			(layer "B.Fab")
		)
		(fp_line
			(start -1.1049 -0.724916)
			(end 1.1049 -0.724916)
			(stroke
				(width 0.1)
				(type default)
			)
			(layer "B.Fab")
		)
		(fp_line
			(start 1.1049 -0.724916)
			(end 1.1049 0.724916)
			(stroke
				(width 0.1)
				(type default)
			)
			(layer "B.Fab")
		)
		(pad "1" smd rect
			(at 0.889 0 270)
			(size 1.016 1.27)
			(layers "B.Cu" "B.Mask" "B.Paste")
			(net "P12V_S3_AUX_CPU0_NVDIMM")
		)
		(pad "2" smd rect
			(at -0.889 0 270)
			(size 1.016 1.27)
			(layers "B.Cu" "B.Mask" "B.Paste")
			(net "GND")
		)
	)
	(footprint ""
		(layer "B.Cu")
		(at 320.039492 -186.440318 90)
		(property "Reference" "R4390"
			(at 0 0 90)
			(layer "B.SilkS")
			(hide yes)
			(effects
				(font
					(size 1.27 1.27)
				)
				(justify mirror)
			)
		)
		(property "Value" ""
			(at 0 0 90)
			(layer "B.Fab")
			(effects
				(font
					(size 1.27 1.27)
				)
				(justify mirror)
			)
		)
		(duplicate_pad_numbers_are_jumpers no)
		(fp_line
			(start 0.7874 -0.4064)
			(end -0.7874 -0.4064)
			(stroke
				(width 0.1524)
				(type default)
			)
			(layer "B.SilkS")
		)
		(fp_line
			(start -0.7874 -0.4064)
			(end -0.7874 0.4064)
			(stroke
				(width 0.1524)
				(type default)
			)
			(layer "B.SilkS")
		)
		(fp_line
			(start 0.7874 0.4064)
			(end 0.7874 -0.4064)
			(stroke
				(width 0.1524)
				(type default)
			)
			(layer "B.SilkS")
		)
		(fp_line
			(start -0.7874 0.4064)
			(end 0.7874 0.4064)
			(stroke
				(width 0.1524)
				(type default)
			)
			(layer "B.SilkS")
		)
		(fp_line
			(start 0.67945 -0.305054)
			(end 0.12065 -0.305054)
			(stroke
				(width 0.1)
				(type default)
			)
			(layer "B.Fab")
		)
		(fp_line
			(start 0.12065 -0.305054)
			(end 0.12065 -0.2794)
			(stroke
				(width 0.1)
				(type default)
			)
			(layer "B.Fab")
		)
		(fp_line
			(start -0.12065 -0.3048)
			(end -0.67945 -0.3048)
			(stroke
				(width 0.1)
				(type default)
			)
			(layer "B.Fab")
		)
		(fp_line
			(start -0.67945 -0.3048)
			(end -0.67945 0.3048)
			(stroke
				(width 0.1)
				(type default)
			)
			(layer "B.Fab")
		)
		(fp_line
			(start 0.12065 -0.2794)
			(end -0.12065 -0.2794)
			(stroke
				(width 0.1)
				(type default)
			)
			(layer "B.Fab")
		)
		(fp_line
			(start -0.12065 -0.2794)
			(end -0.12065 -0.3048)
			(stroke
				(width 0.1)
				(type default)
			)
			(layer "B.Fab")
		)
		(fp_line
			(start 0.12065 0.2794)
			(end 0.12065 0.3048)
			(stroke
				(width 0.1)
				(type default)
			)
			(layer "B.Fab")
		)
		(fp_line
			(start -0.120396 0.2794)
			(end 0.12065 0.2794)
			(stroke
				(width 0.1)
				(type default)
			)
			(layer "B.Fab")
		)
		(fp_line
			(start 0.67945 0.3048)
			(end 0.67945 -0.305054)
			(stroke
				(width 0.1)
				(type default)
			)
			(layer "B.Fab")
		)
		(fp_line
			(start 0.12065 0.3048)
			(end 0.67945 0.3048)
			(stroke
				(width 0.1)
				(type default)
			)
			(layer "B.Fab")
		)
		(fp_line
			(start -0.120396 0.3048)
			(end -0.120396 0.2794)
			(stroke
				(width 0.1)
				(type default)
			)
			(layer "B.Fab")
		)
		(fp_line
			(start -0.67945 0.3048)
			(end -0.120396 0.3048)
			(stroke
				(width 0.1)
				(type default)
			)
			(layer "B.Fab")
		)
		(pad "1" smd circle
			(at 0.40005 0 270)
			(size 0 0)
			(layers "B.Cu" "B.Mask" "B.Paste")
			(net "PVNN_TERM_CPU0")
		)
		(pad "2" smd circle
			(at -0.40005 0 270)
			(size 0 0)
			(layers "B.Cu" "B.Mask" "B.Paste")
			(net "H_CPU_ERR0_LVC1_R_N")
		)
	)
)
